# Bryce Canyon_Front_Panel_Board_Stackup.xlsx — 16369-SC (pcb-stackup)
|  |  |  |  |  |  | Version |  |  |  |  |  |  |  |
| Board Number: |  | 16369-SD |  |  |  | 01 |  |  |  |  |  |  |  |
| Project name: |  | Bryce Canyon |  |  |  |  |  |  |  |  |  |  |  |
| Model Name: |  | Front Panel Board |  |  |  |  |  |  |  |  |  |  |  |
| Layer Count: |  | 4 Layer |  |  |  |  |  |  |  |  |  |  |  |
| Date: |  | 2017-03-28 00:00:00 |  |  |  |  |  |  |  |  |  |  |  |
| Medium Loss Material: |  | IT150G / NPG150N(Tg : 150/Td : 350) |  |  |  |  |  |  |  | Single Ended Type(mil) |  |  |  |
| Golden Finger(Y/N): |  | N |  |  |  |  |  |  | Imp | 50 |  |  |  |
| Customer: |  | <name> |  |  |  |  |  |  | Variation | Inner/Outer+/-5ohm |  |  |  |
| EE engineer |  | <name> |  |  |  |  |  |  | Bus | MISC./I2C |  |  |  |
| SI Engineer |  | <name> |  |  |  |  |  |  |  |  |  |  |  |
|  |  |  |  |  |  |  |  |  | Type | SE |  |  |  |
| Layer |  |  | Thickness |  | Glass/Copper Style | Er |  | Df(1G) | Layers | 1,4 |  |  |  |
|  |  | Cu oz | Wiwynn |  |  | Wiwynn |  |  |  | Wiwynn |  |  |  |
|  | Mask |  | 0.5 |  |  | 3.4 |  |  |  | Width | Imp | Width | Imp |
| Top | Signal | 0.5 oz+plating | 1.9 |  |  |  |  |  | S1 | 6.75(L2) | 49.96 |  |  |
|  | Prepreg |  | 4 |  |  | 4 |  |  |  |  |  |  |  |
| L2 | POWER/GND | 1 oz | 1.3 |  |  |  |  |  | P2 | reference layer |  |  |  |
|  | Core |  | 47.6 |  |  | 4.5 |  |  |  |  |  |  |  |
| L3 | POWER/GND | 1 oz | 1.3 | 0 | 0 |  |  |  | P3 | reference layer |  |  |  |
|  | Prepreg |  | 4 | 0 | 0 | 4 | 0 | 0 |  |  |  |  |  |
| Bottom | Signal | 0.5 oz+plating | 1.9 | 0 | 0 |  |  |  | S4 | 6.75(L3) | 49.96 |  |  |
|  | Mask |  | 0.5 | 0 |  | 3.4 | 0 | 0 |  |  |  |  |  |
| Thickness requirement: 1.6 ± 10% mm |  | mil | 63 |  |  |  |  |  |  |  |  |  |  |
|  |  | mm | 1.6002032004064008 |  |  |  |  |  |  |  |  |  |  |
| Note: | 1. Unit is mil |  |  |  |  |  |  |  |  |  |  |  |  |
|  | 2. The total thickness includes trace and solder mask |  |  |  |  |  |  |  |  |  |  |  |  |
|  | 3. Minimum hole copper thickness is 1.0 mil |  |  |  |  |  |  |  |  |  |  |  |  |
|  | 4. Minimum surface copper thickness 1.5 mil |  |  |  |  |  |  |  |  |  |  |  |  |
|  | 5. If there is no controlled impedance line described as the stackup in the gerber file, PCB supplier can ignore this kind of impedance control directly, but need to inform Wiwynn. |  |  |  |  |  |  |  |  |  |  |  |  |
|  | 6. Impedance Cpk requirement: >=1.33 (Value should be provided in the first article report) |  |  |  |  |  |  |  |  |  |  |  |  |
